(kicad_pcb
	(version 20260206)
	(generator "pcbnew")
	(generator_version "10.0")
	(general
		(thickness 1.6)
		(legacy_teardrops no)
	)
	(paper "A4")
	(title_block
		(title "panther-plus-userver — 13130-1b_20150205.brd")
		(comment 1 "Honey Badger (Wiwynn) / footprints 1063-1070 of 1509")
	)
	(layers
		(0 "F.Cu" signal "TOP")
		(4 "In1.Cu" signal "L2")
		(6 "In2.Cu" signal "L3")
		(8 "In3.Cu" signal "L4")
		(10 "In4.Cu" signal "L5")
		(12 "In5.Cu" signal "L6")
		(14 "In6.Cu" signal "L7")
		(16 "In7.Cu" signal "L8")
		(18 "In8.Cu" signal "L9")
		(20 "In9.Cu" signal "L10")
		(22 "In10.Cu" signal "L11")
		(2 "B.Cu" signal "BOTTOM")
		(9 "F.Adhes" user "F.Adhesive")
		(11 "B.Adhes" user "B.Adhesive")
		(13 "F.Paste" user "Package Geometry/Pastemask Top")
		(15 "B.Paste" user "Package Geometry/Pastemask Bottom")
		(5 "F.SilkS" user "Ref Des/Silkscreen Top")
		(7 "B.SilkS" user "Ref Des/Silkscreen Bottom")
		(1 "F.Mask" user "Board Geometry/Soldermask Top")
		(3 "B.Mask" user "Board Geometry/Soldermask Bottom")
		(17 "Dwgs.User" user "User.Drawings")
		(19 "Cmts.User" user "User.Comments")
		(21 "Eco1.User" user "User.Eco1")
		(23 "Eco2.User" user "User.Eco2")
		(25 "Edge.Cuts" user "Board Geometry/Outline")
		(27 "Margin" user)
		(31 "F.CrtYd" user "Package Geometry/Place Bound Top")
		(29 "B.CrtYd" user "Package Geometry/Place Bound Bottom")
		(35 "F.Fab" user "Ref Des/Assembly Top")
		(33 "B.Fab" user "Ref Des/Assembly Bottom")
	)
	(footprint ""
		(layer "B.Cu")
		(at 100.584 -51.308 180)
		(property "Reference" "R258"
			(at 0 0 0)
			(layer "B.SilkS")
			(hide yes)
			(effects
				(font
					(size 1.27 1.27)
				)
				(justify mirror)
			)
		)
		(property "Value" "1KR2F-3-GP"
			(at -0.064008 -3.993896 180)
			(unlocked yes)
			(layer "B.Fab")
			(hide yes)
			(effects
				(font
					(size 1.016 1.016)
					(thickness 0.1524)
				)
				(justify mirror)
			)
		)
		(property "Device Type" "R402H16"
			(at -0.064008 -5.517896 180)
			(unlocked yes)
			(layer "B.Fab")
			(hide yes)
			(effects
				(font
					(size 1.016 1.016)
					(thickness 0.1524)
				)
				(justify mirror)
			)
		)
		(duplicate_pad_numbers_are_jumpers no)
		(fp_rect
			(start 0.381 0.8382)
			(end -0.381 -0.8382)
			(stroke
				(width 0)
				(type default)
			)
			(fill no)
			(layer "B.CrtYd")
		)
		(fp_rect
			(start 0.381 0.8382)
			(end -0.381 -0.8382)
			(stroke
				(width 0)
				(type default)
			)
			(fill no)
			(layer "B.Fab")
		)
		(pad "1" smd custom
			(at 0 -0.4318)
			(size 0.127 0.127)
			(layers "B.Cu" "B.Mask" "B.Paste")
			(net "PV_VDDR")
			(options
				(clearance outline)
				(anchor circle)
			)
			(primitives
				(gr_poly
					(pts
						(arc
							(start -0.2032 0.2794)
							(mid -0.239121 0.264521)
							(end -0.254 0.2286)
						)
						(arc
							(start -0.254 -0.2286)
							(mid -0.239121 -0.264521)
							(end -0.2032 -0.2794)
						)
						(arc
							(start 0.2032 -0.2794)
							(mid 0.239121 -0.264521)
							(end 0.254 -0.2286)
						)
						(arc
							(start 0.254 0.2286)
							(mid 0.239121 0.264521)
							(end 0.2032 0.2794)
						)
					)
					(width 0)
					(fill yes)
				)
			)
		)
		(pad "2" smd custom
			(at 0 0.4318)
			(size 0.127 0.127)
			(layers "B.Cu" "B.Mask" "B.Paste")
			(net "M_A_RESET#")
			(options
				(clearance outline)
				(anchor circle)
			)
			(primitives
				(gr_poly
					(pts
						(arc
							(start -0.2032 0.2794)
							(mid -0.239121 0.264521)
							(end -0.254 0.2286)
						)
						(arc
							(start -0.254 -0.2286)
							(mid -0.239121 -0.264521)
							(end -0.2032 -0.2794)
						)
						(arc
							(start 0.2032 -0.2794)
							(mid 0.239121 -0.264521)
							(end 0.254 -0.2286)
						)
						(arc
							(start 0.254 0.2286)
							(mid 0.239121 0.264521)
							(end 0.2032 0.2794)
						)
					)
					(width 0)
					(fill yes)
				)
			)
		)
	)
	(footprint ""
		(layer "B.Cu")
		(at 95.9358 -38.6842 -90)
		(property "Reference" "TP29"
			(at 0 0 90)
			(layer "B.SilkS")
			(hide yes)
			(effects
				(font
					(size 1.27 1.27)
				)
				(justify mirror)
			)
		)
		(property "Value" "TPAD24"
			(at 0 -2.9972 270)
			(unlocked yes)
			(layer "B.Fab")
			(hide yes)
			(effects
				(font
					(size 1.016 1.016)
					(thickness 0.1524)
				)
				(justify mirror)
			)
		)
		(property "Device Type" "TPAD24"
			(at 0 -4.5212 270)
			(unlocked yes)
			(layer "B.Fab")
			(hide yes)
			(effects
				(font
					(size 1.016 1.016)
					(thickness 0.1524)
				)
				(justify mirror)
			)
		)
		(duplicate_pad_numbers_are_jumpers no)
		(fp_poly
			(pts
				(arc
					(start 0 -0.3048)
					(mid 0 0.3048)
					(end 0 -0.3048)
				)
			)
			(stroke
				(width 0)
				(type default)
			)
			(fill no)
			(layer "B.CrtYd")
		)
		(fp_poly
			(pts
				(arc
					(start 0 -0.6096)
					(mid 0 0.6096)
					(end 0 -0.6096)
				)
			)
			(stroke
				(width 0)
				(type default)
			)
			(fill no)
			(layer "B.Fab")
		)
		(pad "1" smd circle
			(at 0 0 90)
			(size 0.6096 0.6096)
			(layers "B.Cu" "B.Mask" "B.Paste")
			(net "TP_CPU_RSVD9")
		)
	)
	(footprint ""
		(layer "B.Cu")
		(at 100.29698 -50.064162 -90)
		(property "Reference" "R287"
			(at 0 0 90)
			(layer "B.SilkS")
			(hide yes)
			(effects
				(font
					(size 1.27 1.27)
				)
				(justify mirror)
			)
		)
		(property "Value" "100R2F-L1-GP-U"
			(at -0.064008 -3.993896 270)
			(unlocked yes)
			(layer "B.Fab")
			(hide yes)
			(effects
				(font
					(size 1.016 1.016)
					(thickness 0.1524)
				)
				(justify mirror)
			)
		)
		(property "Device Type" "R402H14"
			(at -0.064008 -5.517896 270)
			(unlocked yes)
			(layer "B.Fab")
			(hide yes)
			(effects
				(font
					(size 1.016 1.016)
					(thickness 0.1524)
				)
				(justify mirror)
			)
		)
		(duplicate_pad_numbers_are_jumpers no)
		(fp_rect
			(start 0.381 0.8382)
			(end -0.381 -0.8382)
			(stroke
				(width 0)
				(type default)
			)
			(fill no)
			(layer "B.CrtYd")
		)
		(fp_rect
			(start 0.381 0.8382)
			(end -0.381 -0.8382)
			(stroke
				(width 0)
				(type default)
			)
			(fill no)
			(layer "B.Fab")
		)
		(pad "1" smd custom
			(at 0 -0.4318 90)
			(size 0.127 0.127)
			(layers "B.Cu" "B.Mask" "B.Paste")
			(net "PV_VDDR")
			(options
				(clearance outline)
				(anchor circle)
			)
			(primitives
				(gr_poly
					(pts
						(arc
							(start -0.2032 0.2794)
							(mid -0.239121 0.264521)
							(end -0.254 0.2286)
						)
						(arc
							(start -0.254 -0.2286)
							(mid -0.239121 -0.264521)
							(end -0.2032 -0.2794)
						)
						(arc
							(start 0.2032 -0.2794)
							(mid 0.239121 -0.264521)
							(end 0.254 -0.2286)
						)
						(arc
							(start 0.254 0.2286)
							(mid 0.239121 0.264521)
							(end 0.2032 0.2794)
						)
					)
					(width 0)
					(fill yes)
				)
			)
		)
		(pad "2" smd custom
			(at 0 0.4318 90)
			(size 0.127 0.127)
			(layers "B.Cu" "B.Mask" "B.Paste")
			(net "M_A_VREF")
			(options
				(clearance outline)
				(anchor circle)
			)
			(primitives
				(gr_poly
					(pts
						(arc
							(start -0.2032 0.2794)
							(mid -0.239121 0.264521)
							(end -0.254 0.2286)
						)
						(arc
							(start -0.254 -0.2286)
							(mid -0.239121 -0.264521)
							(end -0.2032 -0.2794)
						)
						(arc
							(start 0.2032 -0.2794)
							(mid 0.239121 -0.264521)
							(end 0.254 -0.2286)
						)
						(arc
							(start 0.254 0.2286)
							(mid 0.239121 0.264521)
							(end 0.2032 0.2794)
						)
					)
					(width 0)
					(fill yes)
				)
			)
		)
	)
	(footprint ""
		(layer "B.Cu")
		(at 30.734 -53.594 180)
		(property "Reference" "PR177"
			(at 0 0 0)
			(layer "B.SilkS")
			(hide yes)
			(effects
				(font
					(size 1.27 1.27)
				)
				(justify mirror)
			)
		)
		(property "Value" "10KR2F-2-GP"
			(at -1.7907 -1.1176 180)
			(unlocked yes)
			(layer "B.Fab")
			(hide yes)
			(effects
				(font
					(size 1.016 1.016)
					(thickness 0.1524)
				)
				(justify mirror)
			)
		)
		(property "Device Type" "R402H16"
			(at -1.7907 -2.6416 180)
			(unlocked yes)
			(layer "B.Fab")
			(hide yes)
			(effects
				(font
					(size 1.016 1.016)
					(thickness 0.1524)
				)
				(justify mirror)
			)
		)
		(duplicate_pad_numbers_are_jumpers no)
		(fp_rect
			(start 0.381 0.8382)
			(end -0.381 -0.8382)
			(stroke
				(width 0)
				(type default)
			)
			(fill no)
			(layer "B.CrtYd")
		)
		(fp_rect
			(start 0.381 0.8382)
			(end -0.381 -0.8382)
			(stroke
				(width 0)
				(type default)
			)
			(fill no)
			(layer "B.Fab")
		)
		(pad "1" smd custom
			(at 0 -0.4318)
			(size 0.127 0.127)
			(layers "B.Cu" "B.Mask" "B.Paste")
			(net "P1V5_STBY_PG")
			(options
				(clearance outline)
				(anchor circle)
			)
			(primitives
				(gr_poly
					(pts
						(arc
							(start -0.2032 0.2794)
							(mid -0.239121 0.264521)
							(end -0.254 0.2286)
						)
						(arc
							(start -0.254 -0.2286)
							(mid -0.239121 -0.264521)
							(end -0.2032 -0.2794)
						)
						(arc
							(start 0.2032 -0.2794)
							(mid 0.239121 -0.264521)
							(end 0.254 -0.2286)
						)
						(arc
							(start 0.254 0.2286)
							(mid 0.239121 0.264521)
							(end 0.2032 0.2794)
						)
					)
					(width 0)
					(fill yes)
				)
			)
		)
		(pad "2" smd custom
			(at 0 0.4318)
			(size 0.127 0.127)
			(layers "B.Cu" "B.Mask" "B.Paste")
			(net "P3V3_STBY")
			(options
				(clearance outline)
				(anchor circle)
			)
			(primitives
				(gr_poly
					(pts
						(arc
							(start -0.2032 0.2794)
							(mid -0.239121 0.264521)
							(end -0.254 0.2286)
						)
						(arc
							(start -0.254 -0.2286)
							(mid -0.239121 -0.264521)
							(end -0.2032 -0.2794)
						)
						(arc
							(start 0.2032 -0.2794)
							(mid 0.239121 -0.264521)
							(end 0.254 -0.2286)
						)
						(arc
							(start 0.254 0.2286)
							(mid 0.239121 0.264521)
							(end 0.2032 0.2794)
						)
					)
					(width 0)
					(fill yes)
				)
			)
		)
	)
	(footprint ""
		(layer "B.Cu")
		(at 161.6964 -12.447778 180)
		(property "Reference" "C333"
			(at 0 0 0)
			(layer "B.SilkS")
			(hide yes)
			(effects
				(font
					(size 1.27 1.27)
				)
				(justify mirror)
			)
		)
		(property "Value" "SCD1U16V2KX-3GP"
			(at -1.8923 -1.2065 180)
			(unlocked yes)
			(layer "B.Fab")
			(hide yes)
			(effects
				(font
					(size 1.016 1.016)
					(thickness 0.1524)
				)
				(justify mirror)
			)
		)
		(property "Device Type" "C402H22"
			(at -1.8923 -2.7305 180)
			(unlocked yes)
			(layer "B.Fab")
			(hide yes)
			(effects
				(font
					(size 1.016 1.016)
					(thickness 0.1524)
				)
				(justify mirror)
			)
		)
		(duplicate_pad_numbers_are_jumpers no)
		(fp_rect
			(start 0.381 0.7366)
			(end -0.381 -0.7366)
			(stroke
				(width 0)
				(type default)
			)
			(fill no)
			(layer "B.CrtYd")
		)
		(fp_rect
			(start 0.381 0.7366)
			(end -0.381 -0.7366)
			(stroke
				(width 0)
				(type default)
			)
			(fill no)
			(layer "B.Fab")
		)
		(pad "1" smd custom
			(at 0 -0.4572)
			(size 0.1143 0.1143)
			(layers "B.Cu" "B.Mask" "B.Paste")
			(net "PV_VDDR")
			(options
				(clearance outline)
				(anchor circle)
			)
			(primitives
				(gr_poly
					(pts
						(arc
							(start -0.254 0.1778)
							(mid -0.239121 0.213721)
							(end -0.2032 0.2286)
						)
						(arc
							(start 0.2032 0.2286)
							(mid 0.239121 0.213721)
							(end 0.254 0.1778)
						)
						(arc
							(start 0.254 -0.1778)
							(mid 0.239121 -0.213721)
							(end 0.2032 -0.2286)
						)
						(arc
							(start -0.2032 -0.2286)
							(mid -0.239121 -0.213721)
							(end -0.254 -0.1778)
						)
					)
					(width 0)
					(fill yes)
				)
			)
		)
		(pad "2" smd custom
			(at 0 0.4572)
			(size 0.1143 0.1143)
			(layers "B.Cu" "B.Mask" "B.Paste")
			(net "GND")
			(options
				(clearance outline)
				(anchor circle)
			)
			(primitives
				(gr_poly
					(pts
						(arc
							(start -0.254 0.1778)
							(mid -0.239121 0.213721)
							(end -0.2032 0.2286)
						)
						(arc
							(start 0.2032 0.2286)
							(mid 0.239121 0.213721)
							(end 0.254 0.1778)
						)
						(arc
							(start 0.254 -0.1778)
							(mid 0.239121 -0.213721)
							(end 0.2032 -0.2286)
						)
						(arc
							(start -0.2032 -0.2286)
							(mid -0.239121 -0.213721)
							(end -0.254 -0.1778)
						)
					)
					(width 0)
					(fill yes)
				)
			)
		)
	)
	(footprint ""
		(layer "B.Cu")
		(at 104.775 -52.832 90)
		(property "Reference" "C141"
			(at 0 0 90)
			(layer "B.SilkS")
			(hide yes)
			(effects
				(font
					(size 1.27 1.27)
				)
				(justify mirror)
			)
		)
		(property "Value" "SC33P50V2JN-3GP"
			(at -1.1811 -2.7051 90)
			(unlocked yes)
			(layer "B.Fab")
			(hide yes)
			(effects
				(font
					(size 1.016 1.016)
					(thickness 0.1524)
				)
				(justify mirror)
			)
		)
		(property "Device Type" "C402H22"
			(at -1.1811 -4.2291 90)
			(unlocked yes)
			(layer "B.Fab")
			(hide yes)
			(effects
				(font
					(size 1.016 1.016)
					(thickness 0.1524)
				)
				(justify mirror)
			)
		)
		(duplicate_pad_numbers_are_jumpers no)
		(fp_rect
			(start 0.381 0.7366)
			(end -0.381 -0.7366)
			(stroke
				(width 0)
				(type default)
			)
			(fill no)
			(layer "B.CrtYd")
		)
		(fp_rect
			(start 0.381 0.7366)
			(end -0.381 -0.7366)
			(stroke
				(width 0)
				(type default)
			)
			(fill no)
			(layer "B.Fab")
		)
		(pad "1" smd custom
			(at 0 -0.4572 270)
			(size 0.1143 0.1143)
			(layers "B.Cu" "B.Mask" "B.Paste")
			(net "PWRGD_DDR3_VCCA")
			(options
				(clearance outline)
				(anchor circle)
			)
			(primitives
				(gr_poly
					(pts
						(arc
							(start -0.254 0.1778)
							(mid -0.239121 0.213721)
							(end -0.2032 0.2286)
						)
						(arc
							(start 0.2032 0.2286)
							(mid 0.239121 0.213721)
							(end 0.254 0.1778)
						)
						(arc
							(start 0.254 -0.1778)
							(mid 0.239121 -0.213721)
							(end 0.2032 -0.2286)
						)
						(arc
							(start -0.2032 -0.2286)
							(mid -0.239121 -0.213721)
							(end -0.254 -0.1778)
						)
					)
					(width 0)
					(fill yes)
				)
			)
		)
		(pad "2" smd custom
			(at 0 0.4572 270)
			(size 0.1143 0.1143)
			(layers "B.Cu" "B.Mask" "B.Paste")
			(net "GND")
			(options
				(clearance outline)
				(anchor circle)
			)
			(primitives
				(gr_poly
					(pts
						(arc
							(start -0.254 0.1778)
							(mid -0.239121 0.213721)
							(end -0.2032 0.2286)
						)
						(arc
							(start 0.2032 0.2286)
							(mid 0.239121 0.213721)
							(end 0.254 0.1778)
						)
						(arc
							(start 0.254 -0.1778)
							(mid 0.239121 -0.213721)
							(end 0.2032 -0.2286)
						)
						(arc
							(start -0.2032 -0.2286)
							(mid -0.239121 -0.213721)
							(end -0.254 -0.1778)
						)
					)
					(width 0)
					(fill yes)
				)
			)
		)
	)
	(footprint ""
		(layer "B.Cu")
		(at 71.0946 -38.9128 90)
		(property "Reference" "C15"
			(at 0 0 90)
			(layer "B.SilkS")
			(hide yes)
			(effects
				(font
					(size 1.27 1.27)
				)
				(justify mirror)
			)
		)
		(property "Value" "SCD1U10V2KX-5GP"
			(at -1.1811 -2.7051 90)
			(unlocked yes)
			(layer "B.Fab")
			(hide yes)
			(effects
				(font
					(size 1.016 1.016)
					(thickness 0.1524)
				)
				(justify mirror)
			)
		)
		(property "Device Type" "C402H22"
			(at -1.1811 -4.2291 90)
			(unlocked yes)
			(layer "B.Fab")
			(hide yes)
			(effects
				(font
					(size 1.016 1.016)
					(thickness 0.1524)
				)
				(justify mirror)
			)
		)
		(duplicate_pad_numbers_are_jumpers no)
		(fp_rect
			(start 0.381 0.7366)
			(end -0.381 -0.7366)
			(stroke
				(width 0)
				(type default)
			)
			(fill no)
			(layer "B.CrtYd")
		)
		(fp_rect
			(start 0.381 0.7366)
			(end -0.381 -0.7366)
			(stroke
				(width 0)
				(type default)
			)
			(fill no)
			(layer "B.Fab")
		)
		(pad "1" smd custom
			(at 0 -0.4572 270)
			(size 0.1143 0.1143)
			(layers "B.Cu" "B.Mask" "B.Paste")
			(net "P3V3_STBY")
			(options
				(clearance outline)
				(anchor circle)
			)
			(primitives
				(gr_poly
					(pts
						(arc
							(start -0.254 0.1778)
							(mid -0.239121 0.213721)
							(end -0.2032 0.2286)
						)
						(arc
							(start 0.2032 0.2286)
							(mid 0.239121 0.213721)
							(end 0.254 0.1778)
						)
						(arc
							(start 0.254 -0.1778)
							(mid 0.239121 -0.213721)
							(end 0.2032 -0.2286)
						)
						(arc
							(start -0.2032 -0.2286)
							(mid -0.239121 -0.213721)
							(end -0.254 -0.1778)
						)
					)
					(width 0)
					(fill yes)
				)
			)
		)
		(pad "2" smd custom
			(at 0 0.4572 270)
			(size 0.1143 0.1143)
			(layers "B.Cu" "B.Mask" "B.Paste")
			(net "GND")
			(options
				(clearance outline)
				(anchor circle)
			)
			(primitives
				(gr_poly
					(pts
						(arc
							(start -0.254 0.1778)
							(mid -0.239121 0.213721)
							(end -0.2032 0.2286)
						)
						(arc
							(start 0.2032 0.2286)
							(mid 0.239121 0.213721)
							(end 0.254 0.1778)
						)
						(arc
							(start 0.254 -0.1778)
							(mid 0.239121 -0.213721)
							(end 0.2032 -0.2286)
						)
						(arc
							(start -0.2032 -0.2286)
							(mid -0.239121 -0.213721)
							(end -0.254 -0.1778)
						)
					)
					(width 0)
					(fill yes)
				)
			)
		)
	)
	(footprint ""
		(layer "B.Cu")
		(at 74.041 -30.226 90)
		(property "Reference" "R122"
			(at 0 0 90)
			(layer "B.SilkS")
			(hide yes)
			(effects
				(font
					(size 1.27 1.27)
				)
				(justify mirror)
			)
		)
		(property "Value" "10KR2F-2-GP"
			(at -0.064008 -3.993896 90)
			(unlocked yes)
			(layer "B.Fab")
			(hide yes)
			(effects
				(font
					(size 1.016 1.016)
					(thickness 0.1524)
				)
				(justify mirror)
			)
		)
		(property "Device Type" "R402H16"
			(at -0.064008 -5.517896 90)
			(unlocked yes)
			(layer "B.Fab")
			(hide yes)
			(effects
				(font
					(size 1.016 1.016)
					(thickness 0.1524)
				)
				(justify mirror)
			)
		)
		(duplicate_pad_numbers_are_jumpers no)
		(fp_rect
			(start 0.381 0.8382)
			(end -0.381 -0.8382)
			(stroke
				(width 0)
				(type default)
			)
			(fill no)
			(layer "B.CrtYd")
		)
		(fp_rect
			(start 0.381 0.8382)
			(end -0.381 -0.8382)
			(stroke
				(width 0)
				(type default)
			)
			(fill no)
			(layer "B.Fab")
		)
		(pad "1" smd custom
			(at 0 -0.4318 270)
			(size 0.127 0.127)
			(layers "B.Cu" "B.Mask" "B.Paste")
			(net "P3V3_CPU")
			(options
				(clearance outline)
				(anchor circle)
			)
			(primitives
				(gr_poly
					(pts
						(arc
							(start -0.2032 0.2794)
							(mid -0.239121 0.264521)
							(end -0.254 0.2286)
						)
						(arc
							(start -0.254 -0.2286)
							(mid -0.239121 -0.264521)
							(end -0.2032 -0.2794)
						)
						(arc
							(start 0.2032 -0.2794)
							(mid 0.239121 -0.264521)
							(end 0.254 -0.2286)
						)
						(arc
							(start 0.254 0.2286)
							(mid 0.239121 0.264521)
							(end 0.2032 0.2794)
						)
					)
					(width 0)
					(fill yes)
				)
			)
		)
		(pad "2" smd custom
			(at 0 0.4318 270)
			(size 0.127 0.127)
			(layers "B.Cu" "B.Mask" "B.Paste")
			(net "GBE_MDIO_CLK0")
			(options
				(clearance outline)
				(anchor circle)
			)
			(primitives
				(gr_poly
					(pts
						(arc
							(start -0.2032 0.2794)
							(mid -0.239121 0.264521)
							(end -0.254 0.2286)
						)
						(arc
							(start -0.254 -0.2286)
							(mid -0.239121 -0.264521)
							(end -0.2032 -0.2794)
						)
						(arc
							(start 0.2032 -0.2794)
							(mid 0.239121 -0.264521)
							(end 0.254 -0.2286)
						)
						(arc
							(start 0.254 0.2286)
							(mid 0.239121 0.264521)
							(end 0.2032 0.2794)
						)
					)
					(width 0)
					(fill yes)
				)
			)
		)
	)
)
